# BASEBOARD_FAB2 (Tioga Pass) — schematic netlist excerpt (pin names and nets, part order shuffled) for the footprints in the layout excerpt that follows; sources: Cadence DE-HDL packaged netlist, KiCad conversion of Wiwynn_Tioga_Pass_MB.brd

R7D25  RES  33.2 1% CHIP  pkg 0402  page 92 : A = FM_CPU_MSMI_LVT3_R_N ; B = FM_CPU_MSMI_LVT3_N

(kicad_pcb
	(version 20260206)
	(generator "pcbnew")
	(generator_version "10.0")
	(general
		(thickness 1.6)
		(legacy_teardrops no)
	)
	(paper "A4")
	(title_block
		(title "Wiwynn_Tioga_Pass_MB.brd")
		(comment 1 "Tioga Pass / footprints 2250-2250 of 4770")
	)
	(layers
		(0 "F.Cu" signal "TOP")
		(4 "In1.Cu" signal "L2GND")
		(6 "In2.Cu" signal "L3")
		(8 "In3.Cu" signal "L4GND")
		(10 "In4.Cu" signal "L5")
		(12 "In5.Cu" signal "L6GND")
		(14 "In6.Cu" signal "L7VCC")
		(16 "In7.Cu" signal "L8VCC")
		(18 "In8.Cu" signal "L9GND")
		(20 "In9.Cu" signal "L10")
		(22 "In10.Cu" signal "L11GND")
		(24 "In11.Cu" signal "L12")
		(26 "In12.Cu" signal "L13GND")
		(2 "B.Cu" signal "BOTTOM")
		(9 "F.Adhes" user "F.Adhesive")
		(11 "B.Adhes" user "B.Adhesive")
		(13 "F.Paste" user "Package Geometry/Pastemask Top")
		(15 "B.Paste" user "Package Geometry/Pastemask Bottom")
		(5 "F.SilkS" user "Ref Des/Silkscreen Top")
		(7 "B.SilkS" user "Ref Des/Silkscreen Bottom")
		(1 "F.Mask" user "Board Geometry/Soldermask Top")
		(3 "B.Mask" user "Board Geometry/Soldermask Bottom")
		(17 "Dwgs.User" user "User.Drawings")
		(19 "Cmts.User" user "User.Comments")
		(21 "Eco1.User" user "User.Eco1")
		(23 "Eco2.User" user "User.Eco2")
		(25 "Edge.Cuts" user "Board Geometry/Outline")
		(27 "Margin" user)
		(31 "F.CrtYd" user "Package Geometry/Place Bound Top")
		(29 "B.CrtYd" user "Package Geometry/Place Bound Bottom")
		(35 "F.Fab" user "Ref Des/Assembly Top")
		(33 "B.Fab" user "Ref Des/Assembly Bottom")
	)
	(footprint ""
		(layer "F.Cu")
		(at 394.72235 -78.462886 90)
		(property "Reference" "R7D25"
			(at 0 0 90)
			(layer "F.SilkS")
			(hide yes)
			(effects
				(font
					(size 1.27 1.27)
				)
			)
		)
		(property "Value" ""
			(at 0 0 90)
			(layer "F.Fab")
			(effects
				(font
					(size 1.27 1.27)
				)
			)
		)
		(duplicate_pad_numbers_are_jumpers no)
		(fp_poly
			(pts
				(xy -0.2794 -0.1016) (xy 0.2794 -0.1016) (xy 0.2794 0.9906) (xy -0.2794 0.9906)
			)
			(stroke
				(width 0)
				(type default)
			)
			(fill no)
			(layer "F.CrtYd")
		)
		(fp_line
			(start 0.2794 -0.1016)
			(end -0.2794 -0.1016)
			(stroke
				(width 0.1)
				(type default)
			)
			(layer "F.Fab")
		)
		(fp_line
			(start -0.2794 -0.1016)
			(end -0.2794 0.9906)
			(stroke
				(width 0.1)
				(type default)
			)
			(layer "F.Fab")
		)
		(fp_line
			(start 0.2794 0.9906)
			(end 0.2794 -0.1016)
			(stroke
				(width 0.1)
				(type default)
			)
			(layer "F.Fab")
		)
		(fp_line
			(start -0.2794 0.9906)
			(end 0.2794 0.9906)
			(stroke
				(width 0.1)
				(type default)
			)
			(layer "F.Fab")
		)
		(pad "1" smd rect
			(at 0 0 90)
			(size 0.508 0.508)
			(layers "F.Cu" "F.Mask" "F.Paste")
			(net "FM_CPU_MSMI_LVT3_R_N")
		)
		(pad "2" smd rect
			(at 0 0.889 90)
			(size 0.508 0.508)
			(layers "F.Cu" "F.Mask" "F.Paste")
			(net "FM_CPU_MSMI_LVT3_N")
		)
		(zone
			(layer "F.Cu")
			(hatch none 0.5)
			(connect_pads
				(clearance 0)
			)
			(min_thickness 0.25)
			(keepout
				(tracks allowed)
				(vias not_allowed)
				(pads allowed)
				(copperpour not_allowed)
				(footprints allowed)
			)
			(placement
				(enabled no)
				(sheetname "")
			)
			(fill
				(thermal_gap 0.5)
				(thermal_bridge_width 0.5)
				(island_removal_mode 0)
			)
			(polygon
				(pts
					(xy 394.97635 -78.208886) (xy 394.97635 -78.716886) (xy 395.35735 -78.716886) (xy 395.35735 -78.208886)
				)
			)
		)
		(zone
			(layer "F.Cu")
			(hatch none 0.5)
			(connect_pads
				(clearance 0)
			)
			(min_thickness 0.25)
			(keepout
				(tracks not_allowed)
				(vias allowed)
				(pads allowed)
				(copperpour not_allowed)
				(footprints allowed)
			)
			(placement
				(enabled no)
				(sheetname "")
			)
			(fill
				(thermal_gap 0.5)
				(thermal_bridge_width 0.5)
				(island_removal_mode 0)
			)
			(polygon
				(pts
					(xy 395.35735 -78.208886) (xy 395.35735 -78.716886) (xy 394.97635 -78.716886) (xy 394.97635 -78.208886)
				)
			)
		)
	)
)
